# S9S_MB_2U (Grand Teton) — schematic netlist excerpt (pin names and nets, part order shuffled) for the footprints in the layout excerpt that follows; sources: Cadence DE-HDL packaged netlist, KiCad conversion of 03242023_DA0F0TMBIJ0_F0T_Motherboard_J_brd_V01_OCP.brd

R4119  Q_RES  54.9K 1% EMPTY  pkg 0402LF  page 146 : A = P3V3_AUX ; B = GPU_3V3IO_RSVD0_FFU
C2283  Q_CAP  0.1UF 25V 10% X7R  pkg 0402  page 246 : A = P3V3_AUX ; B = GND

(kicad_pcb
	(version 20260206)
	(generator "pcbnew")
	(generator_version "10.0")
	(general
		(thickness 1.6)
		(legacy_teardrops no)
	)
	(paper "A4")
	(title_block
		(title "03242023_DA0F0TMBIJ0_F0T_Motherboard_J_brd_V01_OCP.brd")
		(comment 1 "Grand Teton / footprints 2182-2183 of 6105")
	)
	(layers
		(0 "F.Cu" signal "TOP")
		(4 "In1.Cu" signal "GND")
		(6 "In2.Cu" signal "IN1")
		(8 "In3.Cu" signal "GND1")
		(10 "In4.Cu" signal "IN2")
		(12 "In5.Cu" signal "GND2")
		(14 "In6.Cu" signal "IN3")
		(16 "In7.Cu" signal "GND3")
		(18 "In8.Cu" signal "VCC")
		(20 "In9.Cu" signal "VCC1")
		(22 "In10.Cu" signal "GND4")
		(24 "In11.Cu" signal "IN4")
		(26 "In12.Cu" signal "GND5")
		(28 "In13.Cu" signal "IN5")
		(30 "In14.Cu" signal "GND6")
		(32 "In15.Cu" signal "IN6")
		(34 "In16.Cu" signal "GND7")
		(2 "B.Cu" signal "BOTTOM")
		(9 "F.Adhes" user "F.Adhesive")
		(11 "B.Adhes" user "B.Adhesive")
		(13 "F.Paste" user "Package Geometry/Pastemask Top")
		(15 "B.Paste" user "Package Geometry/Pastemask Bottom")
		(5 "F.SilkS" user "Ref Des/Silkscreen Top")
		(7 "B.SilkS" user "Ref Des/Silkscreen Bottom")
		(1 "F.Mask" user "Board Geometry/Soldermask Top")
		(3 "B.Mask" user "Board Geometry/Soldermask Bottom")
		(17 "Dwgs.User" user "User.Drawings")
		(19 "Cmts.User" user "User.Comments")
		(21 "Eco1.User" user "User.Eco1")
		(23 "Eco2.User" user "User.Eco2")
		(25 "Edge.Cuts" user "Board Geometry/Outline")
		(27 "Margin" user)
		(31 "F.CrtYd" user "Package Geometry/Place Bound Top")
		(29 "B.CrtYd" user "Package Geometry/Place Bound Bottom")
		(35 "F.Fab" user "Ref Des/Assembly Top")
		(33 "B.Fab" user "Ref Des/Assembly Bottom")
	)
	(footprint ""
		(layer "F.Cu")
		(at 302.895 -421.49395 90)
		(property "Reference" "R4119"
			(at 0 0 90)
			(layer "F.SilkS")
			(hide yes)
			(effects
				(font
					(size 1.27 1.27)
				)
			)
		)
		(property "Value" ""
			(at 0 0 90)
			(layer "F.Fab")
			(effects
				(font
					(size 1.27 1.27)
				)
			)
		)
		(duplicate_pad_numbers_are_jumpers no)
		(fp_line
			(start 0.7874 -0.4064)
			(end 0.7874 0.4064)
			(stroke
				(width 0.1524)
				(type default)
			)
			(layer "F.SilkS")
		)
		(fp_line
			(start -0.7874 -0.4064)
			(end 0.7874 -0.4064)
			(stroke
				(width 0.1524)
				(type default)
			)
			(layer "F.SilkS")
		)
		(fp_line
			(start 0.7874 0.4064)
			(end -0.7874 0.4064)
			(stroke
				(width 0.1524)
				(type default)
			)
			(layer "F.SilkS")
		)
		(fp_line
			(start -0.7874 0.4064)
			(end -0.7874 -0.4064)
			(stroke
				(width 0.1524)
				(type default)
			)
			(layer "F.SilkS")
		)
		(fp_line
			(start -0.12065 -0.305054)
			(end -0.12065 -0.2794)
			(stroke
				(width 0.1)
				(type default)
			)
			(layer "F.Fab")
		)
		(fp_line
			(start -0.67945 -0.305054)
			(end -0.12065 -0.305054)
			(stroke
				(width 0.1)
				(type default)
			)
			(layer "F.Fab")
		)
		(fp_line
			(start 0.67945 -0.3048)
			(end 0.67945 0.3048)
			(stroke
				(width 0.1)
				(type default)
			)
			(layer "F.Fab")
		)
		(fp_line
			(start 0.12065 -0.3048)
			(end 0.67945 -0.3048)
			(stroke
				(width 0.1)
				(type default)
			)
			(layer "F.Fab")
		)
		(fp_line
			(start 0.12065 -0.2794)
			(end 0.12065 -0.3048)
			(stroke
				(width 0.1)
				(type default)
			)
			(layer "F.Fab")
		)
		(fp_line
			(start -0.12065 -0.2794)
			(end 0.12065 -0.2794)
			(stroke
				(width 0.1)
				(type default)
			)
			(layer "F.Fab")
		)
		(fp_line
			(start 0.120396 0.2794)
			(end -0.12065 0.2794)
			(stroke
				(width 0.1)
				(type default)
			)
			(layer "F.Fab")
		)
		(fp_line
			(start -0.12065 0.2794)
			(end -0.12065 0.3048)
			(stroke
				(width 0.1)
				(type default)
			)
			(layer "F.Fab")
		)
		(fp_line
			(start 0.67945 0.3048)
			(end 0.120396 0.3048)
			(stroke
				(width 0.1)
				(type default)
			)
			(layer "F.Fab")
		)
		(fp_line
			(start 0.120396 0.3048)
			(end 0.120396 0.2794)
			(stroke
				(width 0.1)
				(type default)
			)
			(layer "F.Fab")
		)
		(fp_line
			(start -0.12065 0.3048)
			(end -0.67945 0.3048)
			(stroke
				(width 0.1)
				(type default)
			)
			(layer "F.Fab")
		)
		(fp_line
			(start -0.67945 0.3048)
			(end -0.67945 -0.305054)
			(stroke
				(width 0.1)
				(type default)
			)
			(layer "F.Fab")
		)
		(pad "1" smd circle
			(at -0.40005 0 90)
			(size 0 0)
			(layers "F.Cu" "F.Mask" "F.Paste")
			(net "P3V3_AUX")
		)
		(pad "2" smd circle
			(at 0.40005 0 90)
			(size 0 0)
			(layers "F.Cu" "F.Mask" "F.Paste")
			(net "GPU_3V3IO_RSVD0_FFU")
		)
	)
	(footprint ""
		(layer "F.Cu")
		(at 307.95087 -425.186602)
		(property "Reference" "C2283"
			(at 0 0 0)
			(layer "F.SilkS")
			(hide yes)
			(effects
				(font
					(size 1.27 1.27)
				)
			)
		)
		(property "Value" ""
			(at 0 0 0)
			(layer "F.Fab")
			(effects
				(font
					(size 1.27 1.27)
				)
			)
		)
		(duplicate_pad_numbers_are_jumpers no)
		(fp_line
			(start -0.7874 -0.4064)
			(end 0.7874 -0.4064)
			(stroke
				(width 0.1524)
				(type default)
			)
			(layer "F.SilkS")
		)
		(fp_line
			(start -0.7874 0.4064)
			(end -0.7874 -0.4064)
			(stroke
				(width 0.1524)
				(type default)
			)
			(layer "F.SilkS")
		)
		(fp_line
			(start 0.7874 -0.4064)
			(end 0.7874 0.4064)
			(stroke
				(width 0.1524)
				(type default)
			)
			(layer "F.SilkS")
		)
		(fp_line
			(start 0.7874 0.4064)
			(end -0.7874 0.4064)
			(stroke
				(width 0.1524)
				(type default)
			)
			(layer "F.SilkS")
		)
		(fp_line
			(start -0.67945 -0.305054)
			(end -0.12065 -0.305054)
			(stroke
				(width 0.1)
				(type default)
			)
			(layer "F.Fab")
		)
		(fp_line
			(start -0.67945 0.3048)
			(end -0.67945 -0.305054)
			(stroke
				(width 0.1)
				(type default)
			)
			(layer "F.Fab")
		)
		(fp_line
			(start -0.12065 -0.305054)
			(end -0.12065 -0.2794)
			(stroke
				(width 0.1)
				(type default)
			)
			(layer "F.Fab")
		)
		(fp_line
			(start -0.12065 -0.2794)
			(end 0.12065 -0.2794)
			(stroke
				(width 0.1)
				(type default)
			)
			(layer "F.Fab")
		)
		(fp_line
			(start -0.12065 0.2794)
			(end -0.12065 0.3048)
			(stroke
				(width 0.1)
				(type default)
			)
			(layer "F.Fab")
		)
		(fp_line
			(start -0.12065 0.3048)
			(end -0.67945 0.3048)
			(stroke
				(width 0.1)
				(type default)
			)
			(layer "F.Fab")
		)
		(fp_line
			(start 0.120396 0.2794)
			(end -0.12065 0.2794)
			(stroke
				(width 0.1)
				(type default)
			)
			(layer "F.Fab")
		)
		(fp_line
			(start 0.120396 0.3048)
			(end 0.120396 0.2794)
			(stroke
				(width 0.1)
				(type default)
			)
			(layer "F.Fab")
		)
		(fp_line
			(start 0.12065 -0.3048)
			(end 0.67945 -0.3048)
			(stroke
				(width 0.1)
				(type default)
			)
			(layer "F.Fab")
		)
		(fp_line
			(start 0.12065 -0.2794)
			(end 0.12065 -0.3048)
			(stroke
				(width 0.1)
				(type default)
			)
			(layer "F.Fab")
		)
		(fp_line
			(start 0.67945 -0.3048)
			(end 0.67945 0.3048)
			(stroke
				(width 0.1)
				(type default)
			)
			(layer "F.Fab")
		)
		(fp_line
			(start 0.67945 0.3048)
			(end 0.120396 0.3048)
			(stroke
				(width 0.1)
				(type default)
			)
			(layer "F.Fab")
		)
		(pad "1" smd circle
			(at -0.40005 0)
			(size 0 0)
			(layers "F.Cu" "F.Mask" "F.Paste")
			(net "P3V3_AUX")
		)
		(pad "2" smd circle
			(at 0.40005 0)
			(size 0 0)
			(layers "F.Cu" "F.Mask" "F.Paste")
			(net "GND")
		)
	)
)
